FILE_TYPE=LIBRARY_PARTS;
primitive 'SWITCH_D90553001','SWITCH_D90553001_SMLF';
  pin
    'A':
      PIN_NUMBER='(1)';
      INPUT_LOAD='(-0.01,0.01)';
    'B':
      PIN_NUMBER='(2)';
      INPUT_LOAD='(-0.01,0.01)';
      OUTPUT_LOAD='(1.0,-1.0)';
      OUTPUT_TYPE='(TS,TS)';
      BIDIRECTIONAL='TRUE';
  end_pin;
  body
    PART_NAME='SWITCH_D90553001';
    PHYS_DES_PREFIX='S';
  end_body;
end_primitive;
END.
